# T6G (Grand Teton) — schematic netlist excerpt (pin names and nets, part order shuffled) for the footprints in the layout excerpt that follows; sources: Cadence DE-HDL packaged netlist, KiCad conversion of 04192023_DAF0TMB3IC0_F0TG_MB_C_brd_V02_OCP.brd

J102  SCONN288_DDR506112002KQ  IO  pkg DDR288S_1-1VXC  page 104
  VIN_BULK0  = P12V_MEM_CPU1
  RFU0  = NC
  VIN_MGMT  = P3V3_AUX
  HSCL  = I3C_SPD_DDRG_CPU1_SCL
  HSDA  = I3C_SPD_DDRG_CPU1_SDA
  VSS0  = GND
  DQ0_A  = M_G_CPU1_SA_DQ<0>
  VSS1  = GND
  DQ1_A  = M_G_CPU1_SA_DQ<1>
  VSS2  = GND
  DQS0_A_T  = M_G_CPU1_SA_DQS_DP<0>
  DQS0_A_C  = M_G_CPU1_SA_DQS_DN<0>
  VSS3  = GND
  DQ4_A  = M_G_CPU1_SA_DQ<4>
  VSS4  = GND
  DQ5_A  = M_G_CPU1_SA_DQ<5>
  VSS5  = GND
  DQ8_A  = M_G_CPU1_SA_DQ<8>
  VSS6  = GND
  DQ9_A  = M_G_CPU1_SA_DQ<9>
  VSS7  = GND
  DQS1_A_T  = M_G_CPU1_SA_DQS_DP<1>
  DQS1_A_C  = M_G_CPU1_SA_DQS_DN<1>
  VSS8  = GND
  DQ12_A  = M_G_CPU1_SA_DQ<12>
  VSS9  = GND
  DQ13_A  = M_G_CPU1_SA_DQ<13>
  VSS10  = GND
  DQ16_A  = M_G_CPU1_SA_DQ<16>
  VSS11  = GND
  DQ17_A  = M_G_CPU1_SA_DQ<17>
  VSS12  = GND
  DQS2_A_T  = M_G_CPU1_SA_DQS_DP<2>
  DQS2_A_C  = M_G_CPU1_SA_DQS_DN<2>
  VSS13  = GND
  DQ20_A  = M_G_CPU1_SA_DQ<20>
  VSS14  = GND
  DQ21_A  = M_G_CPU1_SA_DQ<21>
  VSS15  = GND
  DQ24_A  = M_G_CPU1_SA_DQ<24>
  VSS16  = GND
  DQ25_A  = M_G_CPU1_SA_DQ<25>
  VSS17  = GND
  DQS3_A_T  = M_G_CPU1_SA_DQS_DP<3>
  DQS3_A_C  = M_G_CPU1_SA_DQS_DN<3>
  VSS18  = GND
  DQ28_A  = M_G_CPU1_SA_DQ<28>
  VSS19  = GND
  DQ29_A  = M_G_CPU1_SA_DQ<29>
  VSS20  = GND
  CB0_A  = M_G_CPU1_SA_CB<0>
  VSS21  = GND
  CB1_A  = M_G_CPU1_SA_CB<1>
  VSS22  = GND
  DQS4_A_T  = M_G_CPU1_SA_DQS_DP<4>
  DQS4_A_C  = M_G_CPU1_SA_DQS_DN<4>
  VSS23  = GND
  CB4_A  = M_G_CPU1_SA_CB<4>
  VSS24  = GND
  CB5_A  = M_G_CPU1_SA_CB<5>
  VSS25  = GND
  ALERT_N  = M_G_CPU1_ALERT_N
  VSS26  = GND
  CS0_A_N  = M_G_CPU1_SA_CS_N<0>
  VSS27  = GND
  CA0_A  = M_G_CPU1_SA_CA<0>
  VSS28  = GND
  CA2_A  = M_G_CPU1_SA_CA<2>
  VSS29  = GND
  CA4_A  = M_G_CPU1_SA_CA<4>
  VSS30  = GND
  CA6_A  = M_G_CPU1_SA_CA<6>
  VSS31  = GND
  PAR_A  = M_G_CPU1_SA_PAR
  VSS32  = GND
  CA0_B  = M_G_CPU1_SB_CA<0>
  VSS33  = GND
  CA2_B  = M_G_CPU1_SB_CA<2>
  VSS34  = GND
  CA4_B  = M_G_CPU1_SB_CA<4>
  VSS35  = GND
  CA6_B  = M_G_CPU1_SB_CA<6>
  VSS36  = GND
  CS0_B_N  = M_G_CPU1_SB_CS_N<0>
  VSS37  = GND
  \lbd||rsp_a_n\  = M_G_CPU1_SA_RSP<0>
  \lbs||rsp_b_n\  = M_G_CPU1_SB_RSP<0>
  VSS38  = GND
  CB4_B  = M_G_CPU1_SB_CB<4>
  VSS39  = GND
  CB5_B  = M_G_CPU1_SB_CB<5>
  VSS40  = GND
  \dqs9_b_t||tdqs9_b_t||dbi4_b_n\  = M_G_CPU1_SB_DQS_DP<9>
  \dqs9_b_c||tdqs9_b_c\  = M_G_CPU1_SB_DQS_DN<9>
  VSS41  = GND
  CB0_B  = M_G_CPU1_SB_CB<0>
  VSS42  = GND
  CB1_B  = M_G_CPU1_SB_CB<1>
  VSS43  = GND
  DQ0_B  = M_G_CPU1_SB_DQ<0>
  VSS44  = GND
  DQ1_B  = M_G_CPU1_SB_DQ<1>
  VSS45  = GND
  DQS0_B_T  = M_G_CPU1_SB_DQS_DP<0>
  DQS0_B_C  = M_G_CPU1_SB_DQS_DN<0>
  VSS46  = GND
  DQ4_B  = M_G_CPU1_SB_DQ<4>
  VSS47  = GND
  DQ5_B  = M_G_CPU1_SB_DQ<5>
  VSS48  = GND
  DQ8_B  = M_G_CPU1_SB_DQ<8>
  VSS49  = GND
  DQ9_B  = M_G_CPU1_SB_DQ<9>
  VSS50  = GND
  DQS1_B_T  = M_G_CPU1_SB_DQS_DP<1>
  DQS1_B_C  = M_G_CPU1_SB_DQS_DN<1>
  VSS51  = GND
  DQ12_B  = M_G_CPU1_SB_DQ<12>
  VSS52  = GND
  DQ13_B  = M_G_CPU1_SB_DQ<13>
  VSS53  = GND
  DQ16_B  = M_G_CPU1_SB_DQ<16>
  VSS54  = GND
  DQ17_B  = M_G_CPU1_SB_DQ<17>
  VSS55  = GND
  DQS2_B_T  = M_G_CPU1_SB_DQS_DP<2>
  DQS2_B_C  = M_G_CPU1_SB_DQS_DN<2>
  VSS56  = GND
  DQ20_B  = M_G_CPU1_SB_DQ<20>
  VSS57  = GND
  DQ21_B  = M_G_CPU1_SB_DQ<21>
  VSS58  = GND
  DQ24_B  = M_G_CPU1_SB_DQ<24>
  VSS59  = GND
  DQ25_B  = M_G_CPU1_SB_DQ<25>
  VSS60  = GND
  DQS3_B_T  = M_G_CPU1_SB_DQS_DP<3>
  DQS3_B_C  = M_G_CPU1_SB_DQS_DN<3>
  VSS61  = GND
  DQ28_B  = M_G_CPU1_SB_DQ<28>
  VSS62  = GND
  DQ29_B  = M_G_CPU1_SB_DQ<29>
  VSS63  = GND
  RFU1  = NC
  VIN_BULK1  = P12V_MEM_CPU1
  VIN_BULK2  = P12V_MEM_CPU1
  \pwr_good||fail_n\  = PWRGD_CHG_CPU1_DIMM0
  HAS  = PD_CHG_CPU1_DIMM0_SAA
  RFU2  = NC
  RFU3  = NC
  VSS64  = GND
  DQ2_A  = M_G_CPU1_SA_DQ<2>
  VSS65  = GND
  DQ3_A  = M_G_CPU1_SA_DQ<3>
  VSS66  = GND
  \dqs5_a_c||tdqs5_a_c||dqs5_a_t||tdqs5_a_t\  = M_G_CPU1_SA_DQS_DN<5>
  \dqs5_a_t||tdqs5_a_t\  = M_G_CPU1_SA_DQS_DP<5>
  VSS67  = GND
  DQ6_A  = M_G_CPU1_SA_DQ<6>
  VSS68  = GND
  DQ7_A  = M_G_CPU1_SA_DQ<7>
  VSS69  = GND
  DQ10_A  = M_G_CPU1_SA_DQ<10>
  VSS70  = GND
  DQ11_A  = M_G_CPU1_SA_DQ<11>
  VSS71  = GND
  \dqs6_a_c||tdqs6_a_c||dqs6_a_t||tdqs6_a_t\  = M_G_CPU1_SA_DQS_DN<6>
  \dqs6_a_t||tdqs6_a_t\  = M_G_CPU1_SA_DQS_DP<6>
  VSS72  = GND
  DQ14_A  = M_G_CPU1_SA_DQ<14>
  VSS73  = GND
  DQ15_A  = M_G_CPU1_SA_DQ<15>
  VSS74  = GND
  DQ18_A  = M_G_CPU1_SA_DQ<18>
  VSS75  = GND
  DQ19_A  = M_G_CPU1_SA_DQ<19>
  VSS76  = GND
  \dqs7_a_c||tdqs7_a_c\  = M_G_CPU1_SA_DQS_DN<7>
  \dqs7_a_t||tdqs7_a_t\  = M_G_CPU1_SA_DQS_DP<7>
  VSS77  = GND
  DQ22_A  = M_G_CPU1_SA_DQ<22>
  VSS78  = GND
  DQ23_A  = M_G_CPU1_SA_DQ<23>
  VSS79  = GND
  DQ26_A  = M_G_CPU1_SA_DQ<26>
  VSS80  = GND
  DQ27_A  = M_G_CPU1_SA_DQ<27>
  VSS81  = GND
  \dqs8_a_c||tdqs8_a_c\  = M_G_CPU1_SA_DQS_DN<8>
  \dqs8_a_t||tdqs8_a_t\  = M_G_CPU1_SA_DQS_DP<8>
  VSS82  = GND
  DQ30_A  = M_G_CPU1_SA_DQ<30>
  VSS83  = GND
  DQ31_A  = M_G_CPU1_SA_DQ<31>
  VSS84  = GND
  CB2_A  = M_G_CPU1_SA_CB<2>
  VSS85  = GND
  CB3_A  = M_G_CPU1_SA_CB<3>
  VSS86  = GND
  \dqs9_a_c||tdqs9_a_c\  = M_G_CPU1_SA_DQS_DN<9>
  \dqs9_a_t||tdqs9_a_t\  = M_G_CPU1_SA_DQS_DP<9>
  VSS87  = GND
  CB6_A  = M_G_CPU1_SA_CB<6>
  VSS88  = GND
  CB7_A  = M_G_CPU1_SA_CB<7>
  VSS89  = GND
  RESET_N  = M_G_CPU1_RESET_N
  VSS90  = GND
  CS1_A_N  = M_G_CPU1_SA_CS_N<1>
  VSS91  = GND
  CA1_A  = M_G_CPU1_SA_CA<1>
  VSS92  = GND
  CA3_A  = M_G_CPU1_SA_CA<3>
  VSS93  = GND
  CA5_A  = M_G_CPU1_SA_CA<5>
  VSS94  = GND
  CK_T  = M_G_CPU1_CLK_DP<0>
  CK_C  = M_G_CPU1_CLK_DN<0>
  VSS95  = GND
  RFU4  = NC
  CA1_B  = M_G_CPU1_SB_CA<1>
  VSS96  = GND
  CA3_B  = M_G_CPU1_SB_CA<3>
  VSS97  = GND
  CA5_B  = M_G_CPU1_SB_CA<5>
  VSS98  = GND
  PAR_B  = M_G_CPU1_SB_PAR
  VSS99  = GND
  CS1_B_N  = M_G_CPU1_SB_CS_N<1>
  VSS100  = GND
  RFU5  = NC
  RFU6  = NC
  VSS101  = GND
  CB6_B  = M_G_CPU1_SB_CB<6>
  VSS102  = GND
  CB7_B  = M_G_CPU1_SB_CB<7>
  VSS103  = GND
  DQS4_B_C  = M_G_CPU1_SB_DQS_DN<4>
  DQS4_B_T  = M_G_CPU1_SB_DQS_DP<4>
  VSS104  = GND
  CB2_B  = M_G_CPU1_SB_CB<2>
  VSS105  = GND
  CB3_B  = M_G_CPU1_SB_CB<3>
  VSS106  = GND
  DQ2_B  = M_G_CPU1_SB_DQ<2>
  VSS107  = GND
  DQ3_B  = M_G_CPU1_SB_DQ<3>
  VSS108  = GND
  \dqs5_b_c||tdqs5_b_c\  = M_G_CPU1_SB_DQS_DN<5>
  \dqs5_b_t||tdqs5_b_t\  = M_G_CPU1_SB_DQS_DP<5>
  VSS109  = GND
  DQ6_B  = M_G_CPU1_SB_DQ<6>
  VSS110  = GND
  DQ7_B  = M_G_CPU1_SB_DQ<7>
  VSS111  = GND
  DQ10_B  = M_G_CPU1_SB_DQ<10>
  VSS112  = GND
  DQ11_B  = M_G_CPU1_SB_DQ<11>
  VSS113  = GND
  \dqs6_b_c||tdqs6_b_c\  = M_G_CPU1_SB_DQS_DN<6>
  \dqs6_b_t||tdqs6_b_t\  = M_G_CPU1_SB_DQS_DP<6>
  VSS114  = GND
  DQ14_B  = M_G_CPU1_SB_DQ<14>
  VSS115  = GND
  DQ15_B  = M_G_CPU1_SB_DQ<15>
  VSS116  = GND
  DQ18_B  = M_G_CPU1_SB_DQ<18>
  VSS117  = GND
  DQ19_B  = M_G_CPU1_SB_DQ<19>
  VSS118  = GND
  \dqs7_b_c||tdqs7_b_c\  = M_G_CPU1_SB_DQS_DN<7>
  \dqs7_b_t||tdqs7_b_t\  = M_G_CPU1_SB_DQS_DP<7>
  VSS119  = GND
  DQ22_B  = M_G_CPU1_SB_DQ<22>
  VSS120  = GND
  DQ23_B  = M_G_CPU1_SB_DQ<23>
  VSS121  = GND
  DQ26_B  = M_G_CPU1_SB_DQ<26>
  VSS122  = GND
  DQ27_B  = M_G_CPU1_SB_DQ<27>
  VSS123  = GND
  \dqs8_b_c||tdqs8_b_c\  = M_G_CPU1_SB_DQS_DN<8>
  \dqs8_b_t||tdqs8_b_t\  = M_G_CPU1_SB_DQS_DP<8>
  VSS124  = GND
  DQ30_B  = M_G_CPU1_SB_DQ<30>
  VSS125  = GND
  DQ31_B  = M_G_CPU1_SB_DQ<31>
  VSS126  = GND
  G1  = GND
  G2  = GND
  G3  = GND

(kicad_pcb
	(version 20260206)
	(generator "pcbnew")
	(generator_version "10.0")
	(general
		(thickness 1.6)
		(legacy_teardrops no)
	)
	(paper "A4")
	(title_block
		(title "04192023_DAF0TMB3IC0_F0TG_MB_C_brd_V02_OCP.brd")
		(comment 1 "Grand Teton / footprint 4934 of 8354 (J102), pads 139-184 of 291")
	)
	(layers
		(0 "F.Cu" signal "TOP")
		(4 "In1.Cu" signal "GND")
		(6 "In2.Cu" signal "IN1")
		(8 "In3.Cu" signal "GND1")
		(10 "In4.Cu" signal "IN2")
		(12 "In5.Cu" signal "GND2")
		(14 "In6.Cu" signal "IN3")
		(16 "In7.Cu" signal "GND3")
		(18 "In8.Cu" signal "VCC")
		(20 "In9.Cu" signal "VCC1")
		(22 "In10.Cu" signal "GND4")
		(24 "In11.Cu" signal "IN4")
		(26 "In12.Cu" signal "GND5")
		(28 "In13.Cu" signal "IN5")
		(30 "In14.Cu" signal "GND6")
		(32 "In15.Cu" signal "IN6")
		(34 "In16.Cu" signal "GND7")
		(2 "B.Cu" signal "BOTTOM")
		(9 "F.Adhes" user "F.Adhesive")
		(11 "B.Adhes" user "B.Adhesive")
		(13 "F.Paste" user "Package Geometry/Pastemask Top")
		(15 "B.Paste" user "Package Geometry/Pastemask Bottom")
		(5 "F.SilkS" user "Ref Des/Silkscreen Top")
		(7 "B.SilkS" user "Ref Des/Silkscreen Bottom")
		(1 "F.Mask" user "Board Geometry/Soldermask Top")
		(3 "B.Mask" user "Board Geometry/Soldermask Bottom")
		(17 "Dwgs.User" user "User.Drawings")
		(19 "Cmts.User" user "User.Comments")
		(21 "Eco1.User" user "User.Eco1")
		(23 "Eco2.User" user "User.Eco2")
		(25 "Edge.Cuts" user "Board Geometry/Outline")
		(27 "Margin" user)
		(31 "F.CrtYd" user "Package Geometry/Place Bound Top")
		(29 "B.CrtYd" user "Package Geometry/Place Bound Bottom")
		(35 "F.Fab" user "Ref Des/Assembly Top")
		(33 "B.Fab" user "Ref Des/Assembly Bottom")
	)
	(footprint ""
		(layer "F.Cu")
		(at 166.47795 -255.560322 180)
		(property "Reference" "J102"
			(at -2.7178 -81.857088 0)
			(unlocked yes)
			(layer "F.SilkS")
			(effects
				(font
					(size 0.7874 0.5842)
					(thickness 0.1524)
				)
			)
		)
		(property "Value" ""
			(at 0 0 180)
			(layer "F.Fab")
			(effects
				(font
					(size 1.27 1.27)
				)
			)
		)
		(duplicate_pad_numbers_are_jumpers no)
		(pad "139" smd rect
			(at -2.050034 59.075066 90)
			(size 0.519938 1.4986)
			(layers "F.Cu" "F.Mask" "F.Paste")
			(net "GND")
		)
		(pad "140" smd rect
			(at -2.050034 59.92495 90)
			(size 0.519938 1.4986)
			(layers "F.Cu" "F.Mask" "F.Paste")
			(net "M_G_CPU1_SB_DQ<28>")
		)
		(pad "141" smd rect
			(at -2.050034 60.775088 90)
			(size 0.519938 1.4986)
			(layers "F.Cu" "F.Mask" "F.Paste")
			(net "GND")
		)
		(pad "142" smd rect
			(at -2.050034 61.624972 90)
			(size 0.519938 1.4986)
			(layers "F.Cu" "F.Mask" "F.Paste")
			(net "M_G_CPU1_SB_DQ<29>")
		)
		(pad "143" smd rect
			(at -2.050034 62.47511 90)
			(size 0.519938 1.4986)
			(layers "F.Cu" "F.Mask" "F.Paste")
			(net "GND")
		)
		(pad "144" smd rect
			(at -2.050034 63.324994 90)
			(size 0.519938 1.4986)
			(layers "F.Cu" "F.Mask" "F.Paste")
			(net "Net_2341")
		)
		(pad "145" smd rect
			(at 2.050034 -63.324994 90)
			(size 0.519938 1.4986)
			(layers "F.Cu" "F.Mask" "F.Paste")
			(net "P12V_MEM_CPU1")
		)
		(pad "146" smd rect
			(at 2.050034 -62.47511 90)
			(size 0.519938 1.4986)
			(layers "F.Cu" "F.Mask" "F.Paste")
			(net "P12V_MEM_CPU1")
		)
		(pad "147" smd rect
			(at 2.050034 -61.624972 90)
			(size 0.519938 1.4986)
			(layers "F.Cu" "F.Mask" "F.Paste")
			(net "PWRGD_CHG_CPU1_DIMM0")
		)
		(pad "148" smd rect
			(at 2.050034 -60.775088 90)
			(size 0.519938 1.4986)
			(layers "F.Cu" "F.Mask" "F.Paste")
			(net "PD_CHG_CPU1_DIMM0_SAA")
		)
		(pad "149" smd rect
			(at 2.050034 -59.92495 90)
			(size 0.519938 1.4986)
			(layers "F.Cu" "F.Mask" "F.Paste")
			(net "Net_2342")
		)
		(pad "150" smd rect
			(at 2.050034 -59.075066 90)
			(size 0.519938 1.4986)
			(layers "F.Cu" "F.Mask" "F.Paste")
			(net "Net_2343")
		)
		(pad "151" smd rect
			(at 2.050034 -58.224928 90)
			(size 0.519938 1.4986)
			(layers "F.Cu" "F.Mask" "F.Paste")
			(net "GND")
		)
		(pad "152" smd rect
			(at 2.050034 -57.375044 90)
			(size 0.519938 1.4986)
			(layers "F.Cu" "F.Mask" "F.Paste")
			(net "M_G_CPU1_SA_DQ<2>")
		)
		(pad "153" smd rect
			(at 2.050034 -56.524906 90)
			(size 0.519938 1.4986)
			(layers "F.Cu" "F.Mask" "F.Paste")
			(net "GND")
		)
		(pad "154" smd rect
			(at 2.050034 -55.675022 90)
			(size 0.519938 1.4986)
			(layers "F.Cu" "F.Mask" "F.Paste")
			(net "M_G_CPU1_SA_DQ<3>")
		)
		(pad "155" smd rect
			(at 2.050034 -54.824884 90)
			(size 0.519938 1.4986)
			(layers "F.Cu" "F.Mask" "F.Paste")
			(net "GND")
		)
		(pad "156" smd rect
			(at 2.050034 -53.975 90)
			(size 0.519938 1.4986)
			(layers "F.Cu" "F.Mask" "F.Paste")
			(net "M_G_CPU1_SA_DQS_DN<5>")
		)
		(pad "157" smd rect
			(at 2.050034 -53.125116 90)
			(size 0.519938 1.4986)
			(layers "F.Cu" "F.Mask" "F.Paste")
			(net "M_G_CPU1_SA_DQS_DP<5>")
		)
		(pad "158" smd rect
			(at 2.050034 -52.274978 90)
			(size 0.519938 1.4986)
			(layers "F.Cu" "F.Mask" "F.Paste")
			(net "GND")
		)
		(pad "159" smd rect
			(at 2.050034 -51.425094 90)
			(size 0.519938 1.4986)
			(layers "F.Cu" "F.Mask" "F.Paste")
			(net "M_G_CPU1_SA_DQ<6>")
		)
		(pad "160" smd rect
			(at 2.050034 -50.574956 90)
			(size 0.519938 1.4986)
			(layers "F.Cu" "F.Mask" "F.Paste")
			(net "GND")
		)
		(pad "161" smd rect
			(at 2.050034 -49.725072 90)
			(size 0.519938 1.4986)
			(layers "F.Cu" "F.Mask" "F.Paste")
			(net "M_G_CPU1_SA_DQ<7>")
		)
		(pad "162" smd rect
			(at 2.050034 -48.874934 90)
			(size 0.519938 1.4986)
			(layers "F.Cu" "F.Mask" "F.Paste")
			(net "GND")
		)
		(pad "163" smd rect
			(at 2.050034 -48.02505 90)
			(size 0.519938 1.4986)
			(layers "F.Cu" "F.Mask" "F.Paste")
			(net "M_G_CPU1_SA_DQ<10>")
		)
		(pad "164" smd rect
			(at 2.050034 -47.174912 90)
			(size 0.519938 1.4986)
			(layers "F.Cu" "F.Mask" "F.Paste")
			(net "GND")
		)
		(pad "165" smd rect
			(at 2.050034 -46.325028 90)
			(size 0.519938 1.4986)
			(layers "F.Cu" "F.Mask" "F.Paste")
			(net "M_G_CPU1_SA_DQ<11>")
		)
		(pad "166" smd rect
			(at 2.050034 -45.47489 90)
			(size 0.519938 1.4986)
			(layers "F.Cu" "F.Mask" "F.Paste")
			(net "GND")
		)
		(pad "167" smd rect
			(at 2.050034 -44.625006 90)
			(size 0.519938 1.4986)
			(layers "F.Cu" "F.Mask" "F.Paste")
			(net "M_G_CPU1_SA_DQS_DN<6>")
		)
		(pad "168" smd rect
			(at 2.050034 -43.775122 90)
			(size 0.519938 1.4986)
			(layers "F.Cu" "F.Mask" "F.Paste")
			(net "M_G_CPU1_SA_DQS_DP<6>")
		)
		(pad "169" smd rect
			(at 2.050034 -42.924984 90)
			(size 0.519938 1.4986)
			(layers "F.Cu" "F.Mask" "F.Paste")
			(net "GND")
		)
		(pad "170" smd rect
			(at 2.050034 -42.0751 90)
			(size 0.519938 1.4986)
			(layers "F.Cu" "F.Mask" "F.Paste")
			(net "M_G_CPU1_SA_DQ<14>")
		)
		(pad "171" smd rect
			(at 2.050034 -41.224962 90)
			(size 0.519938 1.4986)
			(layers "F.Cu" "F.Mask" "F.Paste")
			(net "GND")
		)
		(pad "172" smd rect
			(at 2.050034 -40.375078 90)
			(size 0.519938 1.4986)
			(layers "F.Cu" "F.Mask" "F.Paste")
			(net "M_G_CPU1_SA_DQ<15>")
		)
		(pad "173" smd rect
			(at 2.050034 -39.52494 90)
			(size 0.519938 1.4986)
			(layers "F.Cu" "F.Mask" "F.Paste")
			(net "GND")
		)
		(pad "174" smd rect
			(at 2.050034 -38.675056 90)
			(size 0.519938 1.4986)
			(layers "F.Cu" "F.Mask" "F.Paste")
			(net "M_G_CPU1_SA_DQ<18>")
		)
		(pad "175" smd rect
			(at 2.050034 -37.824918 90)
			(size 0.519938 1.4986)
			(layers "F.Cu" "F.Mask" "F.Paste")
			(net "GND")
		)
		(pad "176" smd rect
			(at 2.050034 -36.975034 90)
			(size 0.519938 1.4986)
			(layers "F.Cu" "F.Mask" "F.Paste")
			(net "M_G_CPU1_SA_DQ<19>")
		)
		(pad "177" smd rect
			(at 2.050034 -36.124896 90)
			(size 0.519938 1.4986)
			(layers "F.Cu" "F.Mask" "F.Paste")
			(net "GND")
		)
		(pad "178" smd rect
			(at 2.050034 -35.275012 90)
			(size 0.519938 1.4986)
			(layers "F.Cu" "F.Mask" "F.Paste")
			(net "M_G_CPU1_SA_DQS_DN<7>")
		)
		(pad "179" smd rect
			(at 2.050034 -34.425128 90)
			(size 0.519938 1.4986)
			(layers "F.Cu" "F.Mask" "F.Paste")
			(net "M_G_CPU1_SA_DQS_DP<7>")
		)
		(pad "180" smd rect
			(at 2.050034 -33.57499 90)
			(size 0.519938 1.4986)
			(layers "F.Cu" "F.Mask" "F.Paste")
			(net "GND")
		)
		(pad "181" smd rect
			(at 2.050034 -32.725106 90)
			(size 0.519938 1.4986)
			(layers "F.Cu" "F.Mask" "F.Paste")
			(net "M_G_CPU1_SA_DQ<22>")
		)
		(pad "182" smd rect
			(at 2.050034 -31.874968 90)
			(size 0.519938 1.4986)
			(layers "F.Cu" "F.Mask" "F.Paste")
			(net "GND")
		)
		(pad "183" smd rect
			(at 2.050034 -31.025084 90)
			(size 0.519938 1.4986)
			(layers "F.Cu" "F.Mask" "F.Paste")
			(net "M_G_CPU1_SA_DQ<23>")
		)
		(pad "184" smd rect
			(at 2.050034 -30.174946 90)
			(size 0.519938 1.4986)
			(layers "F.Cu" "F.Mask" "F.Paste")
			(net "GND")
		)
	)
)
